(kicad_pcb
	(version 20260206)
	(generator "pcbnew")
	(generator_version "10.0")
	(general
		(thickness 1.6)
		(legacy_teardrops no)
	)
	(paper "A4")
	(title_block
		(title "04192023_DAF0TMB3IC0_F0TG_MB_C_brd_V02_OCP.brd")
		(comment 1 "Grand Teton / footprint 1120 of 8354 (J15), pads 227-291 of 291")
	)
	(layers
		(0 "F.Cu" signal "TOP")
		(4 "In1.Cu" signal "GND")
		(6 "In2.Cu" signal "IN1")
		(8 "In3.Cu" signal "GND1")
		(10 "In4.Cu" signal "IN2")
		(12 "In5.Cu" signal "GND2")
		(14 "In6.Cu" signal "IN3")
		(16 "In7.Cu" signal "GND3")
		(18 "In8.Cu" signal "VCC")
		(20 "In9.Cu" signal "VCC1")
		(22 "In10.Cu" signal "GND4")
		(24 "In11.Cu" signal "IN4")
		(26 "In12.Cu" signal "GND5")
		(28 "In13.Cu" signal "IN5")
		(30 "In14.Cu" signal "GND6")
		(32 "In15.Cu" signal "IN6")
		(34 "In16.Cu" signal "GND7")
		(2 "B.Cu" signal "BOTTOM")
		(9 "F.Adhes" user "F.Adhesive")
		(11 "B.Adhes" user "B.Adhesive")
		(13 "F.Paste" user "Package Geometry/Pastemask Top")
		(15 "B.Paste" user "Package Geometry/Pastemask Bottom")
		(5 "F.SilkS" user "Ref Des/Silkscreen Top")
		(7 "B.SilkS" user "Ref Des/Silkscreen Bottom")
		(1 "F.Mask" user "Board Geometry/Soldermask Top")
		(3 "B.Mask" user "Board Geometry/Soldermask Bottom")
		(17 "Dwgs.User" user "User.Drawings")
		(19 "Cmts.User" user "User.Comments")
		(21 "Eco1.User" user "User.Eco1")
		(23 "Eco2.User" user "User.Eco2")
		(25 "Edge.Cuts" user "Board Geometry/Outline")
		(27 "Margin" user)
		(31 "F.CrtYd" user "Package Geometry/Place Bound Top")
		(29 "B.CrtYd" user "Package Geometry/Place Bound Bottom")
		(35 "F.Fab" user "Ref Des/Assembly Top")
		(33 "B.Fab" user "Ref Des/Assembly Bottom")
	)
	(footprint ""
		(layer "F.Cu")
		(at 297.774106 -255.560068 180)
		(property "Reference" "J15"
			(at -2.2098 -81.984088 0)
			(unlocked yes)
			(layer "F.SilkS")
			(effects
				(font
					(size 0.7874 0.5842)
					(thickness 0.1524)
				)
			)
		)
		(property "Value" ""
			(at 0 0 180)
			(layer "F.Fab")
			(effects
				(font
					(size 1.27 1.27)
				)
			)
		)
		(duplicate_pad_numbers_are_jumpers no)
		(pad "227" smd rect
			(at 2.050034 11.474958 90)
			(size 0.519938 1.4986)
			(layers "F.Cu" "F.Mask" "F.Paste")
			(net "M_B_CPU0_SB_PAR")
		)
		(pad "228" smd rect
			(at 2.050034 12.325096 90)
			(size 0.519938 1.4986)
			(layers "F.Cu" "F.Mask" "F.Paste")
			(net "GND")
		)
		(pad "229" smd rect
			(at 2.050034 13.17498 90)
			(size 0.519938 1.4986)
			(layers "F.Cu" "F.Mask" "F.Paste")
			(net "M_B_CPU0_SB_CS_N<1>")
		)
		(pad "230" smd rect
			(at 2.050034 14.025118 90)
			(size 0.519938 1.4986)
			(layers "F.Cu" "F.Mask" "F.Paste")
			(net "GND")
		)
		(pad "231" smd rect
			(at 2.050034 14.875002 90)
			(size 0.519938 1.4986)
			(layers "F.Cu" "F.Mask" "F.Paste")
			(net "Net_2268")
		)
		(pad "232" smd rect
			(at 2.050034 15.724886 90)
			(size 0.519938 1.4986)
			(layers "F.Cu" "F.Mask" "F.Paste")
			(net "Net_2269")
		)
		(pad "233" smd rect
			(at 2.050034 16.575024 90)
			(size 0.519938 1.4986)
			(layers "F.Cu" "F.Mask" "F.Paste")
			(net "GND")
		)
		(pad "234" smd rect
			(at 2.050034 17.424908 90)
			(size 0.519938 1.4986)
			(layers "F.Cu" "F.Mask" "F.Paste")
			(net "M_B_CPU0_SB_CB<6>")
		)
		(pad "235" smd rect
			(at 2.050034 18.275046 90)
			(size 0.519938 1.4986)
			(layers "F.Cu" "F.Mask" "F.Paste")
			(net "GND")
		)
		(pad "236" smd rect
			(at 2.050034 19.12493 90)
			(size 0.519938 1.4986)
			(layers "F.Cu" "F.Mask" "F.Paste")
			(net "M_B_CPU0_SB_CB<7>")
		)
		(pad "237" smd rect
			(at 2.050034 19.975068 90)
			(size 0.519938 1.4986)
			(layers "F.Cu" "F.Mask" "F.Paste")
			(net "GND")
		)
		(pad "238" smd rect
			(at 2.050034 20.824952 90)
			(size 0.519938 1.4986)
			(layers "F.Cu" "F.Mask" "F.Paste")
			(net "M_B_CPU0_SB_DQS_DN<4>")
		)
		(pad "239" smd rect
			(at 2.050034 21.67509 90)
			(size 0.519938 1.4986)
			(layers "F.Cu" "F.Mask" "F.Paste")
			(net "M_B_CPU0_SB_DQS_DP<4>")
		)
		(pad "240" smd rect
			(at 2.050034 22.524974 90)
			(size 0.519938 1.4986)
			(layers "F.Cu" "F.Mask" "F.Paste")
			(net "GND")
		)
		(pad "241" smd rect
			(at 2.050034 23.375112 90)
			(size 0.519938 1.4986)
			(layers "F.Cu" "F.Mask" "F.Paste")
			(net "M_B_CPU0_SB_CB<2>")
		)
		(pad "242" smd rect
			(at 2.050034 24.224996 90)
			(size 0.519938 1.4986)
			(layers "F.Cu" "F.Mask" "F.Paste")
			(net "GND")
		)
		(pad "243" smd rect
			(at 2.050034 25.07488 90)
			(size 0.519938 1.4986)
			(layers "F.Cu" "F.Mask" "F.Paste")
			(net "M_B_CPU0_SB_CB<3>")
		)
		(pad "244" smd rect
			(at 2.050034 25.925018 90)
			(size 0.519938 1.4986)
			(layers "F.Cu" "F.Mask" "F.Paste")
			(net "GND")
		)
		(pad "245" smd rect
			(at 2.050034 26.774902 90)
			(size 0.519938 1.4986)
			(layers "F.Cu" "F.Mask" "F.Paste")
			(net "M_B_CPU0_SB_DQ<2>")
		)
		(pad "246" smd rect
			(at 2.050034 27.62504 90)
			(size 0.519938 1.4986)
			(layers "F.Cu" "F.Mask" "F.Paste")
			(net "GND")
		)
		(pad "247" smd rect
			(at 2.050034 28.474924 90)
			(size 0.519938 1.4986)
			(layers "F.Cu" "F.Mask" "F.Paste")
			(net "M_B_CPU0_SB_DQ<3>")
		)
		(pad "248" smd rect
			(at 2.050034 29.325062 90)
			(size 0.519938 1.4986)
			(layers "F.Cu" "F.Mask" "F.Paste")
			(net "GND")
		)
		(pad "249" smd rect
			(at 2.050034 30.174946 90)
			(size 0.519938 1.4986)
			(layers "F.Cu" "F.Mask" "F.Paste")
			(net "M_B_CPU0_SB_DQS_DN<5>")
		)
		(pad "250" smd rect
			(at 2.050034 31.025084 90)
			(size 0.519938 1.4986)
			(layers "F.Cu" "F.Mask" "F.Paste")
			(net "M_B_CPU0_SB_DQS_DP<5>")
		)
		(pad "251" smd rect
			(at 2.050034 31.874968 90)
			(size 0.519938 1.4986)
			(layers "F.Cu" "F.Mask" "F.Paste")
			(net "GND")
		)
		(pad "252" smd rect
			(at 2.050034 32.725106 90)
			(size 0.519938 1.4986)
			(layers "F.Cu" "F.Mask" "F.Paste")
			(net "M_B_CPU0_SB_DQ<6>")
		)
		(pad "253" smd rect
			(at 2.050034 33.57499 90)
			(size 0.519938 1.4986)
			(layers "F.Cu" "F.Mask" "F.Paste")
			(net "GND")
		)
		(pad "254" smd rect
			(at 2.050034 34.425128 90)
			(size 0.519938 1.4986)
			(layers "F.Cu" "F.Mask" "F.Paste")
			(net "M_B_CPU0_SB_DQ<7>")
		)
		(pad "255" smd rect
			(at 2.050034 35.275012 90)
			(size 0.519938 1.4986)
			(layers "F.Cu" "F.Mask" "F.Paste")
			(net "GND")
		)
		(pad "256" smd rect
			(at 2.050034 36.124896 90)
			(size 0.519938 1.4986)
			(layers "F.Cu" "F.Mask" "F.Paste")
			(net "M_B_CPU0_SB_DQ<10>")
		)
		(pad "257" smd rect
			(at 2.050034 36.975034 90)
			(size 0.519938 1.4986)
			(layers "F.Cu" "F.Mask" "F.Paste")
			(net "GND")
		)
		(pad "258" smd rect
			(at 2.050034 37.824918 90)
			(size 0.519938 1.4986)
			(layers "F.Cu" "F.Mask" "F.Paste")
			(net "M_B_CPU0_SB_DQ<11>")
		)
		(pad "259" smd rect
			(at 2.050034 38.675056 90)
			(size 0.519938 1.4986)
			(layers "F.Cu" "F.Mask" "F.Paste")
			(net "GND")
		)
		(pad "260" smd rect
			(at 2.050034 39.52494 90)
			(size 0.519938 1.4986)
			(layers "F.Cu" "F.Mask" "F.Paste")
			(net "M_B_CPU0_SB_DQS_DN<6>")
		)
		(pad "261" smd rect
			(at 2.050034 40.375078 90)
			(size 0.519938 1.4986)
			(layers "F.Cu" "F.Mask" "F.Paste")
			(net "M_B_CPU0_SB_DQS_DP<6>")
		)
		(pad "262" smd rect
			(at 2.050034 41.224962 90)
			(size 0.519938 1.4986)
			(layers "F.Cu" "F.Mask" "F.Paste")
			(net "GND")
		)
		(pad "263" smd rect
			(at 2.050034 42.0751 90)
			(size 0.519938 1.4986)
			(layers "F.Cu" "F.Mask" "F.Paste")
			(net "M_B_CPU0_SB_DQ<14>")
		)
		(pad "264" smd rect
			(at 2.050034 42.924984 90)
			(size 0.519938 1.4986)
			(layers "F.Cu" "F.Mask" "F.Paste")
			(net "GND")
		)
		(pad "265" smd rect
			(at 2.050034 43.775122 90)
			(size 0.519938 1.4986)
			(layers "F.Cu" "F.Mask" "F.Paste")
			(net "M_B_CPU0_SB_DQ<15>")
		)
		(pad "266" smd rect
			(at 2.050034 44.625006 90)
			(size 0.519938 1.4986)
			(layers "F.Cu" "F.Mask" "F.Paste")
			(net "GND")
		)
		(pad "267" smd rect
			(at 2.050034 45.47489 90)
			(size 0.519938 1.4986)
			(layers "F.Cu" "F.Mask" "F.Paste")
			(net "M_B_CPU0_SB_DQ<18>")
		)
		(pad "268" smd rect
			(at 2.050034 46.325028 90)
			(size 0.519938 1.4986)
			(layers "F.Cu" "F.Mask" "F.Paste")
			(net "GND")
		)
		(pad "269" smd rect
			(at 2.050034 47.174912 90)
			(size 0.519938 1.4986)
			(layers "F.Cu" "F.Mask" "F.Paste")
			(net "M_B_CPU0_SB_DQ<19>")
		)
		(pad "270" smd rect
			(at 2.050034 48.02505 90)
			(size 0.519938 1.4986)
			(layers "F.Cu" "F.Mask" "F.Paste")
			(net "GND")
		)
		(pad "271" smd rect
			(at 2.050034 48.874934 90)
			(size 0.519938 1.4986)
			(layers "F.Cu" "F.Mask" "F.Paste")
			(net "M_B_CPU0_SB_DQS_DN<7>")
		)
		(pad "272" smd rect
			(at 2.050034 49.725072 90)
			(size 0.519938 1.4986)
			(layers "F.Cu" "F.Mask" "F.Paste")
			(net "M_B_CPU0_SB_DQS_DP<7>")
		)
		(pad "273" smd rect
			(at 2.050034 50.574956 90)
			(size 0.519938 1.4986)
			(layers "F.Cu" "F.Mask" "F.Paste")
			(net "GND")
		)
		(pad "274" smd rect
			(at 2.050034 51.425094 90)
			(size 0.519938 1.4986)
			(layers "F.Cu" "F.Mask" "F.Paste")
			(net "M_B_CPU0_SB_DQ<22>")
		)
		(pad "275" smd rect
			(at 2.050034 52.274978 90)
			(size 0.519938 1.4986)
			(layers "F.Cu" "F.Mask" "F.Paste")
			(net "GND")
		)
		(pad "276" smd rect
			(at 2.050034 53.125116 90)
			(size 0.519938 1.4986)
			(layers "F.Cu" "F.Mask" "F.Paste")
			(net "M_B_CPU0_SB_DQ<23>")
		)
		(pad "277" smd rect
			(at 2.050034 53.975 90)
			(size 0.519938 1.4986)
			(layers "F.Cu" "F.Mask" "F.Paste")
			(net "GND")
		)
		(pad "278" smd rect
			(at 2.050034 54.824884 90)
			(size 0.519938 1.4986)
			(layers "F.Cu" "F.Mask" "F.Paste")
			(net "M_B_CPU0_SB_DQ<26>")
		)
		(pad "279" smd rect
			(at 2.050034 55.675022 90)
			(size 0.519938 1.4986)
			(layers "F.Cu" "F.Mask" "F.Paste")
			(net "GND")
		)
		(pad "280" smd rect
			(at 2.050034 56.524906 90)
			(size 0.519938 1.4986)
			(layers "F.Cu" "F.Mask" "F.Paste")
			(net "M_B_CPU0_SB_DQ<27>")
		)
		(pad "281" smd rect
			(at 2.050034 57.375044 90)
			(size 0.519938 1.4986)
			(layers "F.Cu" "F.Mask" "F.Paste")
			(net "GND")
		)
		(pad "282" smd rect
			(at 2.050034 58.224928 90)
			(size 0.519938 1.4986)
			(layers "F.Cu" "F.Mask" "F.Paste")
			(net "M_B_CPU0_SB_DQS_DN<8>")
		)
		(pad "283" smd rect
			(at 2.050034 59.075066 90)
			(size 0.519938 1.4986)
			(layers "F.Cu" "F.Mask" "F.Paste")
			(net "M_B_CPU0_SB_DQS_DP<8>")
		)
		(pad "284" smd rect
			(at 2.050034 59.92495 90)
			(size 0.519938 1.4986)
			(layers "F.Cu" "F.Mask" "F.Paste")
			(net "GND")
		)
		(pad "285" smd rect
			(at 2.050034 60.775088 90)
			(size 0.519938 1.4986)
			(layers "F.Cu" "F.Mask" "F.Paste")
			(net "M_B_CPU0_SB_DQ<30>")
		)
		(pad "286" smd rect
			(at 2.050034 61.624972 90)
			(size 0.519938 1.4986)
			(layers "F.Cu" "F.Mask" "F.Paste")
			(net "GND")
		)
		(pad "287" smd rect
			(at 2.050034 62.47511 90)
			(size 0.519938 1.4986)
			(layers "F.Cu" "F.Mask" "F.Paste")
			(net "M_B_CPU0_SB_DQ<31>")
		)
		(pad "288" smd rect
			(at 2.050034 63.324994 90)
			(size 0.519938 1.4986)
			(layers "F.Cu" "F.Mask" "F.Paste")
			(net "GND")
		)
		(pad "G1" thru_hole oval
			(at 0 -68.97497 90)
			(size 1.7272 3.4798)
			(drill oval 1.2192 2.4638)
			(layers "*.Cu" "*.Mask")
			(remove_unused_layers no)
			(net "GND")
			(clearance 0.127)
			(thermal_gap 0.127)
		)
		(pad "G2" thru_hole oval
			(at 0 3.875024 90)
			(size 1.7272 3.4798)
			(drill oval 1.2192 2.4638)
			(layers "*.Cu" "*.Mask")
			(remove_unused_layers no)
			(net "GND")
			(clearance 0.127)
			(thermal_gap 0.127)
		)
		(pad "G3" thru_hole oval
			(at 0 68.97497 90)
			(size 1.7272 3.4798)
			(drill oval 1.2192 2.4638)
			(layers "*.Cu" "*.Mask")
			(remove_unused_layers no)
			(net "GND")
			(clearance 0.127)
			(thermal_gap 0.127)
		)
	)
)
